(kicad_pcb
	(version 20260206)
	(generator "pcbnew")
	(generator_version "10.0")
	(general
		(thickness 1.6)
		(legacy_teardrops no)
	)
	(paper "A4")
	(title_block
		(title "Wiwynn_Tioga_Pass_MB.brd")
		(comment 1 "Tioga Pass / footprints 4410-4416 of 4770")
	)
	(layers
		(0 "F.Cu" signal "TOP")
		(4 "In1.Cu" signal "L2GND")
		(6 "In2.Cu" signal "L3")
		(8 "In3.Cu" signal "L4GND")
		(10 "In4.Cu" signal "L5")
		(12 "In5.Cu" signal "L6GND")
		(14 "In6.Cu" signal "L7VCC")
		(16 "In7.Cu" signal "L8VCC")
		(18 "In8.Cu" signal "L9GND")
		(20 "In9.Cu" signal "L10")
		(22 "In10.Cu" signal "L11GND")
		(24 "In11.Cu" signal "L12")
		(26 "In12.Cu" signal "L13GND")
		(2 "B.Cu" signal "BOTTOM")
		(9 "F.Adhes" user "F.Adhesive")
		(11 "B.Adhes" user "B.Adhesive")
		(13 "F.Paste" user "Package Geometry/Pastemask Top")
		(15 "B.Paste" user "Package Geometry/Pastemask Bottom")
		(5 "F.SilkS" user "Ref Des/Silkscreen Top")
		(7 "B.SilkS" user "Ref Des/Silkscreen Bottom")
		(1 "F.Mask" user "Board Geometry/Soldermask Top")
		(3 "B.Mask" user "Board Geometry/Soldermask Bottom")
		(17 "Dwgs.User" user "User.Drawings")
		(19 "Cmts.User" user "User.Comments")
		(21 "Eco1.User" user "User.Eco1")
		(23 "Eco2.User" user "User.Eco2")
		(25 "Edge.Cuts" user "Board Geometry/Outline")
		(27 "Margin" user)
		(31 "F.CrtYd" user "Package Geometry/Place Bound Top")
		(29 "B.CrtYd" user "Package Geometry/Place Bound Bottom")
		(35 "F.Fab" user "Ref Des/Assembly Top")
		(33 "B.Fab" user "Ref Des/Assembly Bottom")
	)
	(footprint ""
		(layer "B.Cu")
		(at 483.785164 -17.036542 90)
		(property "Reference" "R9G2"
			(at 0 0 90)
			(layer "B.SilkS")
			(hide yes)
			(effects
				(font
					(size 1.27 1.27)
				)
				(justify mirror)
			)
		)
		(property "Value" ""
			(at 0 0 90)
			(layer "B.Fab")
			(effects
				(font
					(size 1.27 1.27)
				)
				(justify mirror)
			)
		)
		(duplicate_pad_numbers_are_jumpers no)
		(fp_poly
			(pts
				(xy 0.2794 -0.1016) (xy -0.2794 -0.1016) (xy -0.2794 0.9906) (xy 0.2794 0.9906)
			)
			(stroke
				(width 0)
				(type default)
			)
			(fill no)
			(layer "B.CrtYd")
		)
		(fp_line
			(start 0.2794 -0.1016)
			(end 0.2794 0.9906)
			(stroke
				(width 0.1)
				(type default)
			)
			(layer "B.Fab")
		)
		(fp_line
			(start -0.2794 -0.1016)
			(end 0.2794 -0.1016)
			(stroke
				(width 0.1)
				(type default)
			)
			(layer "B.Fab")
		)
		(fp_line
			(start 0.2794 0.9906)
			(end -0.2794 0.9906)
			(stroke
				(width 0.1)
				(type default)
			)
			(layer "B.Fab")
		)
		(fp_line
			(start -0.2794 0.9906)
			(end -0.2794 -0.1016)
			(stroke
				(width 0.1)
				(type default)
			)
			(layer "B.Fab")
		)
		(pad "1" smd rect
			(at 0 0 270)
			(size 0.508 0.508)
			(layers "B.Cu" "B.Mask" "B.Paste")
			(net "LED_LAN_2_R_N")
		)
		(pad "2" smd rect
			(at 0 0.889 270)
			(size 0.508 0.508)
			(layers "B.Cu" "B.Mask" "B.Paste")
			(net "LED_LAN_2_N")
		)
		(zone
			(layer "B.Cu")
			(hatch none 0.5)
			(connect_pads
				(clearance 0)
			)
			(min_thickness 0.25)
			(keepout
				(tracks allowed)
				(vias not_allowed)
				(pads allowed)
				(copperpour not_allowed)
				(footprints allowed)
			)
			(placement
				(enabled no)
				(sheetname "")
			)
			(fill
				(thermal_gap 0.5)
				(thermal_bridge_width 0.5)
				(island_removal_mode 0)
			)
			(polygon
				(pts
					(xy 484.039164 -17.290542) (xy 484.039164 -16.782542) (xy 484.420164 -16.782542) (xy 484.420164 -17.290542)
				)
			)
		)
		(zone
			(layer "B.Cu")
			(hatch none 0.5)
			(connect_pads
				(clearance 0)
			)
			(min_thickness 0.25)
			(keepout
				(tracks not_allowed)
				(vias allowed)
				(pads allowed)
				(copperpour not_allowed)
				(footprints allowed)
			)
			(placement
				(enabled no)
				(sheetname "")
			)
			(fill
				(thermal_gap 0.5)
				(thermal_bridge_width 0.5)
				(island_removal_mode 0)
			)
			(polygon
				(pts
					(xy 484.420164 -17.290542) (xy 484.420164 -16.782542) (xy 484.039164 -16.782542) (xy 484.039164 -17.290542)
				)
			)
		)
	)
	(footprint ""
		(layer "B.Cu")
		(at 330.4794 -11.7094)
		(property "Reference" "R4U2"
			(at 0 0 0)
			(layer "B.SilkS")
			(hide yes)
			(effects
				(font
					(size 1.27 1.27)
				)
				(justify mirror)
			)
		)
		(property "Value" ""
			(at 0 0 0)
			(layer "B.Fab")
			(effects
				(font
					(size 1.27 1.27)
				)
				(justify mirror)
			)
		)
		(duplicate_pad_numbers_are_jumpers no)
		(fp_poly
			(pts
				(xy 0.2794 -0.1016) (xy -0.2794 -0.1016) (xy -0.2794 0.9906) (xy 0.2794 0.9906)
			)
			(stroke
				(width 0)
				(type default)
			)
			(fill no)
			(layer "B.CrtYd")
		)
		(fp_line
			(start -0.2794 -0.1016)
			(end 0.2794 -0.1016)
			(stroke
				(width 0.1)
				(type default)
			)
			(layer "B.Fab")
		)
		(fp_line
			(start -0.2794 0.9906)
			(end -0.2794 -0.1016)
			(stroke
				(width 0.1)
				(type default)
			)
			(layer "B.Fab")
		)
		(fp_line
			(start 0.2794 -0.1016)
			(end 0.2794 0.9906)
			(stroke
				(width 0.1)
				(type default)
			)
			(layer "B.Fab")
		)
		(fp_line
			(start 0.2794 0.9906)
			(end -0.2794 0.9906)
			(stroke
				(width 0.1)
				(type default)
			)
			(layer "B.Fab")
		)
		(pad "1" smd rect
			(at 0 0 180)
			(size 0.508 0.508)
			(layers "B.Cu" "B.Mask" "B.Paste")
			(net "PVPP_ABC")
		)
		(pad "2" smd rect
			(at 0 0.889 180)
			(size 0.508 0.508)
			(layers "B.Cu" "B.Mask" "B.Paste")
			(net "FM_DIMM_EVENT_COD_N")
		)
		(zone
			(layer "B.Cu")
			(hatch none 0.5)
			(connect_pads
				(clearance 0)
			)
			(min_thickness 0.25)
			(keepout
				(tracks allowed)
				(vias not_allowed)
				(pads allowed)
				(copperpour not_allowed)
				(footprints allowed)
			)
			(placement
				(enabled no)
				(sheetname "")
			)
			(fill
				(thermal_gap 0.5)
				(thermal_bridge_width 0.5)
				(island_removal_mode 0)
			)
			(polygon
				(pts
					(xy 330.7334 -11.4554) (xy 330.2254 -11.4554) (xy 330.2254 -11.0744) (xy 330.7334 -11.0744)
				)
			)
		)
		(zone
			(layer "B.Cu")
			(hatch none 0.5)
			(connect_pads
				(clearance 0)
			)
			(min_thickness 0.25)
			(keepout
				(tracks not_allowed)
				(vias allowed)
				(pads allowed)
				(copperpour not_allowed)
				(footprints allowed)
			)
			(placement
				(enabled no)
				(sheetname "")
			)
			(fill
				(thermal_gap 0.5)
				(thermal_bridge_width 0.5)
				(island_removal_mode 0)
			)
			(polygon
				(pts
					(xy 330.7334 -11.0744) (xy 330.2254 -11.0744) (xy 330.2254 -11.4554) (xy 330.7334 -11.4554)
				)
			)
		)
	)
	(footprint ""
		(layer "B.Cu")
		(at 347.79204 -149.168104 -90)
		(property "Reference" "C7A26"
			(at 0 0 90)
			(layer "B.SilkS")
			(hide yes)
			(effects
				(font
					(size 1.27 1.27)
				)
				(justify mirror)
			)
		)
		(property "Value" "*"
			(at -1.1811 -2.8194 270)
			(unlocked yes)
			(layer "B.Fab")
			(hide yes)
			(effects
				(font
					(size 1.27 1.016)
					(thickness 0.1524)
				)
				(justify mirror)
			)
		)
		(property "Device Type" "SC1U10V2KX-4-GP_SMD-BCG6-SC1U1A"
			(at -1.1811 -4.3434 270)
			(unlocked yes)
			(layer "B.Fab")
			(hide yes)
			(effects
				(font
					(size 1.27 1.016)
					(thickness 0.1524)
				)
				(justify mirror)
			)
		)
		(duplicate_pad_numbers_are_jumpers no)
		(fp_rect
			(start 0.4318 0.9525)
			(end -0.4318 -0.9525)
			(stroke
				(width 0)
				(type default)
			)
			(fill no)
			(layer "B.CrtYd")
		)
		(fp_rect
			(start 0.4318 0.9525)
			(end -0.4318 -0.9525)
			(stroke
				(width 0)
				(type default)
			)
			(fill no)
			(layer "B.Fab")
		)
		(pad "1" smd custom
			(at 0 -0.4445 90)
			(size 0.1524 0.1524)
			(layers "B.Cu" "B.Mask" "B.Paste")
			(net "P5V_STBY")
			(options
				(clearance outline)
				(anchor circle)
			)
			(primitives
				(gr_poly
					(pts
						(arc
							(start 0.3048 0.2032)
							(mid 0.275042 0.275042)
							(end 0.2032 0.3048)
						)
						(arc
							(start -0.2032 0.3048)
							(mid -0.275042 0.275042)
							(end -0.3048 0.2032)
						)
						(arc
							(start -0.3048 -0.2032)
							(mid -0.275042 -0.275042)
							(end -0.2032 -0.3048)
						)
						(arc
							(start 0.2032 -0.3048)
							(mid 0.275042 -0.275042)
							(end 0.3048 -0.2032)
						)
					)
					(width 0)
					(fill yes)
				)
			)
		)
		(pad "2" smd custom
			(at 0 0.4445 90)
			(size 0.1524 0.1524)
			(layers "B.Cu" "B.Mask" "B.Paste")
			(net "GND")
			(options
				(clearance outline)
				(anchor circle)
			)
			(primitives
				(gr_poly
					(pts
						(arc
							(start 0.3048 0.2032)
							(mid 0.275042 0.275042)
							(end 0.2032 0.3048)
						)
						(arc
							(start -0.2032 0.3048)
							(mid -0.275042 0.275042)
							(end -0.3048 0.2032)
						)
						(arc
							(start -0.3048 -0.2032)
							(mid -0.275042 -0.275042)
							(end -0.2032 -0.3048)
						)
						(arc
							(start 0.2032 -0.3048)
							(mid 0.275042 -0.275042)
							(end 0.3048 -0.2032)
						)
					)
					(width 0)
					(fill yes)
				)
			)
		)
	)
	(footprint ""
		(layer "B.Cu")
		(at 468.63 -46.6725 180)
		(property "Reference" "R9E12"
			(at 0 0 0)
			(layer "B.SilkS")
			(hide yes)
			(effects
				(font
					(size 1.27 1.27)
				)
				(justify mirror)
			)
		)
		(property "Value" ""
			(at 0 0 0)
			(layer "B.Fab")
			(effects
				(font
					(size 1.27 1.27)
				)
				(justify mirror)
			)
		)
		(duplicate_pad_numbers_are_jumpers no)
		(fp_poly
			(pts
				(xy 0.2794 -0.1016) (xy -0.2794 -0.1016) (xy -0.2794 0.9906) (xy 0.2794 0.9906)
			)
			(stroke
				(width 0)
				(type default)
			)
			(fill no)
			(layer "B.CrtYd")
		)
		(fp_line
			(start 0.2794 0.9906)
			(end -0.2794 0.9906)
			(stroke
				(width 0.1)
				(type default)
			)
			(layer "B.Fab")
		)
		(fp_line
			(start 0.2794 -0.1016)
			(end 0.2794 0.9906)
			(stroke
				(width 0.1)
				(type default)
			)
			(layer "B.Fab")
		)
		(fp_line
			(start -0.2794 0.9906)
			(end -0.2794 -0.1016)
			(stroke
				(width 0.1)
				(type default)
			)
			(layer "B.Fab")
		)
		(fp_line
			(start -0.2794 -0.1016)
			(end 0.2794 -0.1016)
			(stroke
				(width 0.1)
				(type default)
			)
			(layer "B.Fab")
		)
		(pad "1" smd rect
			(at 0 0)
			(size 0.508 0.508)
			(layers "B.Cu" "B.Mask" "B.Paste")
			(net "RST_PCIE_CPU_DEV3_R_N")
		)
		(pad "2" smd rect
			(at 0 0.889)
			(size 0.508 0.508)
			(layers "B.Cu" "B.Mask" "B.Paste")
			(net "RST_PCIE_CPU_DEV3_N")
		)
		(zone
			(layer "B.Cu")
			(hatch none 0.5)
			(connect_pads
				(clearance 0)
			)
			(min_thickness 0.25)
			(keepout
				(tracks not_allowed)
				(vias allowed)
				(pads allowed)
				(copperpour not_allowed)
				(footprints allowed)
			)
			(placement
				(enabled no)
				(sheetname "")
			)
			(fill
				(thermal_gap 0.5)
				(thermal_bridge_width 0.5)
				(island_removal_mode 0)
			)
			(polygon
				(pts
					(xy 468.376 -47.3075) (xy 468.884 -47.3075) (xy 468.884 -46.9265) (xy 468.376 -46.9265)
				)
			)
		)
		(zone
			(layer "B.Cu")
			(hatch none 0.5)
			(connect_pads
				(clearance 0)
			)
			(min_thickness 0.25)
			(keepout
				(tracks allowed)
				(vias not_allowed)
				(pads allowed)
				(copperpour not_allowed)
				(footprints allowed)
			)
			(placement
				(enabled no)
				(sheetname "")
			)
			(fill
				(thermal_gap 0.5)
				(thermal_bridge_width 0.5)
				(island_removal_mode 0)
			)
			(polygon
				(pts
					(xy 468.376 -46.9265) (xy 468.884 -46.9265) (xy 468.884 -47.3075) (xy 468.376 -47.3075)
				)
			)
		)
	)
	(footprint ""
		(layer "B.Cu")
		(at -1.44526 -119.46636 180)
		(property "Reference" "R9M16"
			(at 0 0 0)
			(layer "B.SilkS")
			(hide yes)
			(effects
				(font
					(size 1.27 1.27)
				)
				(justify mirror)
			)
		)
		(property "Value" ""
			(at 0 0 0)
			(layer "B.Fab")
			(effects
				(font
					(size 1.27 1.27)
				)
				(justify mirror)
			)
		)
		(duplicate_pad_numbers_are_jumpers no)
		(fp_rect
			(start 0.2794 -0.1016)
			(end -0.2794 0.9906)
			(stroke
				(width 0)
				(type default)
			)
			(fill no)
			(layer "B.CrtYd")
		)
		(fp_line
			(start 0.2794 0.9906)
			(end -0.2794 0.9906)
			(stroke
				(width 0.1)
				(type default)
			)
			(layer "B.Fab")
		)
		(fp_line
			(start 0.2794 -0.1016)
			(end 0.2794 0.9906)
			(stroke
				(width 0.1)
				(type default)
			)
			(layer "B.Fab")
		)
		(fp_line
			(start -0.2794 0.9906)
			(end -0.2794 -0.1016)
			(stroke
				(width 0.1)
				(type default)
			)
			(layer "B.Fab")
		)
		(fp_line
			(start -0.2794 -0.1016)
			(end 0.2794 -0.1016)
			(stroke
				(width 0.1)
				(type default)
			)
			(layer "B.Fab")
		)
		(pad "1" smd rect
			(at 0 0)
			(size 0.508 0.508)
			(layers "B.Cu" "B.Mask" "B.Paste")
			(net "P3V3_STBY")
		)
		(pad "2" smd rect
			(at 0 0.889)
			(size 0.508 0.508)
			(layers "B.Cu" "B.Mask" "B.Paste")
			(net "SMB_PEHPCPU1_STBY_LVC3_R_SDA")
		)
		(zone
			(layer "B.Cu")
			(hatch none 0.5)
			(connect_pads
				(clearance 0)
			)
			(min_thickness 0.25)
			(keepout
				(tracks allowed)
				(vias not_allowed)
				(pads allowed)
				(copperpour not_allowed)
				(footprints allowed)
			)
			(placement
				(enabled no)
				(sheetname "")
			)
			(fill
				(thermal_gap 0.5)
				(thermal_bridge_width 0.5)
				(island_removal_mode 0)
			)
			(polygon
				(pts
					(xy -1.69926 -119.72036) (xy -1.19126 -119.72036) (xy -1.19126 -120.10136) (xy -1.69926 -120.10136)
				)
			)
		)
		(zone
			(layer "B.Cu")
			(hatch none 0.5)
			(connect_pads
				(clearance 0)
			)
			(min_thickness 0.25)
			(keepout
				(tracks not_allowed)
				(vias allowed)
				(pads allowed)
				(copperpour not_allowed)
				(footprints allowed)
			)
			(placement
				(enabled no)
				(sheetname "")
			)
			(fill
				(thermal_gap 0.5)
				(thermal_bridge_width 0.5)
				(island_removal_mode 0)
			)
			(polygon
				(pts
					(xy -1.69926 -119.72036) (xy -1.19126 -119.72036) (xy -1.19126 -120.10136) (xy -1.69926 -120.10136)
				)
			)
		)
	)
	(footprint ""
		(layer "B.Cu")
		(at 484.9749 -49.8602 90)
		(property "Reference" "R1R1"
			(at 0 0 90)
			(layer "B.SilkS")
			(hide yes)
			(effects
				(font
					(size 1.27 1.27)
				)
				(justify mirror)
			)
		)
		(property "Value" ""
			(at 0 0 90)
			(layer "B.Fab")
			(effects
				(font
					(size 1.27 1.27)
				)
				(justify mirror)
			)
		)
		(duplicate_pad_numbers_are_jumpers no)
		(fp_poly
			(pts
				(xy 0.2794 -0.1016) (xy -0.2794 -0.1016) (xy -0.2794 0.9906) (xy 0.2794 0.9906)
			)
			(stroke
				(width 0)
				(type default)
			)
			(fill no)
			(layer "B.CrtYd")
		)
		(fp_line
			(start 0.2794 -0.1016)
			(end 0.2794 0.9906)
			(stroke
				(width 0.1)
				(type default)
			)
			(layer "B.Fab")
		)
		(fp_line
			(start -0.2794 -0.1016)
			(end 0.2794 -0.1016)
			(stroke
				(width 0.1)
				(type default)
			)
			(layer "B.Fab")
		)
		(fp_line
			(start 0.2794 0.9906)
			(end -0.2794 0.9906)
			(stroke
				(width 0.1)
				(type default)
			)
			(layer "B.Fab")
		)
		(fp_line
			(start -0.2794 0.9906)
			(end -0.2794 -0.1016)
			(stroke
				(width 0.1)
				(type default)
			)
			(layer "B.Fab")
		)
		(pad "1" smd rect
			(at 0 0 270)
			(size 0.508 0.508)
			(layers "B.Cu" "B.Mask" "B.Paste")
			(net "RST_PLTRST_N")
		)
		(pad "2" smd rect
			(at 0 0.889 270)
			(size 0.508 0.508)
			(layers "B.Cu" "B.Mask" "B.Paste")
			(net "RST_PLTRST_SPRV_R_N")
		)
		(zone
			(layer "B.Cu")
			(hatch none 0.5)
			(connect_pads
				(clearance 0)
			)
			(min_thickness 0.25)
			(keepout
				(tracks allowed)
				(vias not_allowed)
				(pads allowed)
				(copperpour not_allowed)
				(footprints allowed)
			)
			(placement
				(enabled no)
				(sheetname "")
			)
			(fill
				(thermal_gap 0.5)
				(thermal_bridge_width 0.5)
				(island_removal_mode 0)
			)
			(polygon
				(pts
					(xy 485.2289 -50.1142) (xy 485.2289 -49.6062) (xy 485.6099 -49.6062) (xy 485.6099 -50.1142)
				)
			)
		)
		(zone
			(layer "B.Cu")
			(hatch none 0.5)
			(connect_pads
				(clearance 0)
			)
			(min_thickness 0.25)
			(keepout
				(tracks not_allowed)
				(vias allowed)
				(pads allowed)
				(copperpour not_allowed)
				(footprints allowed)
			)
			(placement
				(enabled no)
				(sheetname "")
			)
			(fill
				(thermal_gap 0.5)
				(thermal_bridge_width 0.5)
				(island_removal_mode 0)
			)
			(polygon
				(pts
					(xy 485.6099 -50.1142) (xy 485.6099 -49.6062) (xy 485.2289 -49.6062) (xy 485.2289 -50.1142)
				)
			)
		)
	)
	(footprint ""
		(layer "B.Cu")
		(at 448.55638 -35.8775 90)
		(property "Reference" "R25W32"
			(at 0 0 90)
			(layer "B.SilkS")
			(hide yes)
			(effects
				(font
					(size 1.27 1.27)
				)
				(justify mirror)
			)
		)
		(property "Value" "*"
			(at -0.064008 -4.108196 90)
			(unlocked yes)
			(layer "B.Fab")
			(hide yes)
			(effects
				(font
					(size 1.27 1.016)
					(thickness 0.1524)
				)
				(justify mirror)
			)
		)
		(property "Device Type" "120R2F-GP_RCL_GP-120R2F-GP,64.A"
			(at -0.064008 -5.632196 90)
			(unlocked yes)
			(layer "B.Fab")
			(hide yes)
			(effects
				(font
					(size 1.27 1.016)
					(thickness 0.1524)
				)
				(justify mirror)
			)
		)
		(duplicate_pad_numbers_are_jumpers no)
		(fp_line
			(start 0.508 -0.9398)
			(end 0.508 0.9398)
			(stroke
				(width 0.1524)
				(type default)
			)
			(layer "B.SilkS")
		)
		(fp_line
			(start -0.508 -0.9398)
			(end 0.508 -0.9398)
			(stroke
				(width 0.1524)
				(type default)
			)
			(layer "B.SilkS")
		)
		(fp_rect
			(start 0.508 0.9398)
			(end -0.508 -0.9398)
			(stroke
				(width 0)
				(type default)
			)
			(fill no)
			(layer "B.CrtYd")
		)
		(fp_rect
			(start 0.508 0.9398)
			(end -0.508 -0.9398)
			(stroke
				(width 0)
				(type default)
			)
			(fill no)
			(layer "B.Fab")
		)
		(pad "1" smd custom
			(at 0 -0.4445 270)
			(size 0.1397 0.1397)
			(layers "B.Cu" "B.Mask" "B.Paste")
			(net "BMC_M_RAS_N")
			(options
				(clearance outline)
				(anchor circle)
			)
			(primitives
				(gr_poly
					(pts
						(arc
							(start -0.1778 0.2794)
							(mid -0.249642 0.249642)
							(end -0.2794 0.1778)
						)
						(arc
							(start -0.2794 -0.1778)
							(mid -0.249642 -0.249642)
							(end -0.1778 -0.2794)
						)
						(arc
							(start 0.1778 -0.2794)
							(mid 0.249642 -0.249642)
							(end 0.2794 -0.1778)
						)
						(arc
							(start 0.2794 0.1778)
							(mid 0.249642 0.249642)
							(end 0.1778 0.2794)
						)
					)
					(width 0)
					(fill yes)
				)
			)
		)
		(pad "2" smd custom
			(at 0 0.4445 270)
			(size 0.1397 0.1397)
			(layers "B.Cu" "B.Mask" "B.Paste")
			(net "P1V2_AUX_BMC")
			(options
				(clearance outline)
				(anchor circle)
			)
			(primitives
				(gr_poly
					(pts
						(arc
							(start -0.1778 0.2794)
							(mid -0.249642 0.249642)
							(end -0.2794 0.1778)
						)
						(arc
							(start -0.2794 -0.1778)
							(mid -0.249642 -0.249642)
							(end -0.1778 -0.2794)
						)
						(arc
							(start 0.1778 -0.2794)
							(mid 0.249642 -0.249642)
							(end 0.2794 -0.1778)
						)
						(arc
							(start 0.2794 0.1778)
							(mid 0.249642 0.249642)
							(end 0.1778 0.2794)
						)
					)
					(width 0)
					(fill yes)
				)
			)
		)
	)
)
